# T6G (Grand Teton) — schematic netlist excerpt (pin names and nets, part order shuffled) for the footprints in the layout excerpt that follows; sources: Cadence DE-HDL packaged netlist, KiCad conversion of 04192023_DAF0TMB3IC0_F0TG_MB_C_brd_V02_OCP.brd

R202  Q_RES  0 5% CHIP  pkg 0402LF  page 160 : A = SMB_CPU0_CPU1_APML_BUF2_SCL_R1 ; B = SMB_CPU0_CPU1_APML_BUF2_SCL_R2
R3090  Q_RES  130 1% CHIP  pkg 0402LF  page 255 : A = LED_PWRGD_PVDD11_S3_P0_R ; B = P3V3_AUX

(kicad_pcb
	(version 20260206)
	(generator "pcbnew")
	(generator_version "10.0")
	(general
		(thickness 1.6)
		(legacy_teardrops no)
	)
	(paper "A4")
	(title_block
		(title "04192023_DAF0TMB3IC0_F0TG_MB_C_brd_V02_OCP.brd")
		(comment 1 "Grand Teton / footprints 5418-5419 of 8354")
	)
	(layers
		(0 "F.Cu" signal "TOP")
		(4 "In1.Cu" signal "GND")
		(6 "In2.Cu" signal "IN1")
		(8 "In3.Cu" signal "GND1")
		(10 "In4.Cu" signal "IN2")
		(12 "In5.Cu" signal "GND2")
		(14 "In6.Cu" signal "IN3")
		(16 "In7.Cu" signal "GND3")
		(18 "In8.Cu" signal "VCC")
		(20 "In9.Cu" signal "VCC1")
		(22 "In10.Cu" signal "GND4")
		(24 "In11.Cu" signal "IN4")
		(26 "In12.Cu" signal "GND5")
		(28 "In13.Cu" signal "IN5")
		(30 "In14.Cu" signal "GND6")
		(32 "In15.Cu" signal "IN6")
		(34 "In16.Cu" signal "GND7")
		(2 "B.Cu" signal "BOTTOM")
		(9 "F.Adhes" user "F.Adhesive")
		(11 "B.Adhes" user "B.Adhesive")
		(13 "F.Paste" user "Package Geometry/Pastemask Top")
		(15 "B.Paste" user "Package Geometry/Pastemask Bottom")
		(5 "F.SilkS" user "Ref Des/Silkscreen Top")
		(7 "B.SilkS" user "Ref Des/Silkscreen Bottom")
		(1 "F.Mask" user "Board Geometry/Soldermask Top")
		(3 "B.Mask" user "Board Geometry/Soldermask Bottom")
		(17 "Dwgs.User" user "User.Drawings")
		(19 "Cmts.User" user "User.Comments")
		(21 "Eco1.User" user "User.Eco1")
		(23 "Eco2.User" user "User.Eco2")
		(25 "Edge.Cuts" user "Board Geometry/Outline")
		(27 "Margin" user)
		(31 "F.CrtYd" user "Package Geometry/Place Bound Top")
		(29 "B.CrtYd" user "Package Geometry/Place Bound Bottom")
		(35 "F.Fab" user "Ref Des/Assembly Top")
		(33 "B.Fab" user "Ref Des/Assembly Bottom")
	)
	(footprint ""
		(layer "B.Cu")
		(at 231.267 -218.059 90)
		(property "Reference" "R202"
			(at 0 0 90)
			(layer "B.SilkS")
			(hide yes)
			(effects
				(font
					(size 1.27 1.27)
				)
				(justify mirror)
			)
		)
		(property "Value" ""
			(at 0 0 90)
			(layer "B.Fab")
			(effects
				(font
					(size 1.27 1.27)
				)
				(justify mirror)
			)
		)
		(duplicate_pad_numbers_are_jumpers no)
		(fp_line
			(start 0.7874 -0.4064)
			(end -0.7874 -0.4064)
			(stroke
				(width 0.1524)
				(type default)
			)
			(layer "B.SilkS")
		)
		(fp_line
			(start -0.7874 -0.4064)
			(end -0.7874 0.4064)
			(stroke
				(width 0.1524)
				(type default)
			)
			(layer "B.SilkS")
		)
		(fp_line
			(start 0.7874 0.4064)
			(end 0.7874 -0.4064)
			(stroke
				(width 0.1524)
				(type default)
			)
			(layer "B.SilkS")
		)
		(fp_line
			(start -0.7874 0.4064)
			(end 0.7874 0.4064)
			(stroke
				(width 0.1524)
				(type default)
			)
			(layer "B.SilkS")
		)
		(fp_line
			(start 0.67945 -0.305054)
			(end 0.12065 -0.305054)
			(stroke
				(width 0.1)
				(type default)
			)
			(layer "B.Fab")
		)
		(fp_line
			(start 0.12065 -0.305054)
			(end 0.12065 -0.2794)
			(stroke
				(width 0.1)
				(type default)
			)
			(layer "B.Fab")
		)
		(fp_line
			(start -0.12065 -0.3048)
			(end -0.67945 -0.3048)
			(stroke
				(width 0.1)
				(type default)
			)
			(layer "B.Fab")
		)
		(fp_line
			(start -0.67945 -0.3048)
			(end -0.67945 0.3048)
			(stroke
				(width 0.1)
				(type default)
			)
			(layer "B.Fab")
		)
		(fp_line
			(start 0.12065 -0.2794)
			(end -0.12065 -0.2794)
			(stroke
				(width 0.1)
				(type default)
			)
			(layer "B.Fab")
		)
		(fp_line
			(start -0.12065 -0.2794)
			(end -0.12065 -0.3048)
			(stroke
				(width 0.1)
				(type default)
			)
			(layer "B.Fab")
		)
		(fp_line
			(start 0.12065 0.2794)
			(end 0.12065 0.3048)
			(stroke
				(width 0.1)
				(type default)
			)
			(layer "B.Fab")
		)
		(fp_line
			(start -0.120396 0.2794)
			(end 0.12065 0.2794)
			(stroke
				(width 0.1)
				(type default)
			)
			(layer "B.Fab")
		)
		(fp_line
			(start 0.67945 0.3048)
			(end 0.67945 -0.305054)
			(stroke
				(width 0.1)
				(type default)
			)
			(layer "B.Fab")
		)
		(fp_line
			(start 0.12065 0.3048)
			(end 0.67945 0.3048)
			(stroke
				(width 0.1)
				(type default)
			)
			(layer "B.Fab")
		)
		(fp_line
			(start -0.120396 0.3048)
			(end -0.120396 0.2794)
			(stroke
				(width 0.1)
				(type default)
			)
			(layer "B.Fab")
		)
		(fp_line
			(start -0.67945 0.3048)
			(end -0.120396 0.3048)
			(stroke
				(width 0.1)
				(type default)
			)
			(layer "B.Fab")
		)
		(pad "1" smd circle
			(at 0.40005 0 270)
			(size 0 0)
			(layers "B.Cu" "B.Mask" "B.Paste")
			(net "SMB_CPU0_CPU1_APML_BUF2_SCL_R1")
		)
		(pad "2" smd circle
			(at -0.40005 0 270)
			(size 0 0)
			(layers "B.Cu" "B.Mask" "B.Paste")
			(net "SMB_CPU0_CPU1_APML_BUF2_SCL_R2")
		)
	)
	(footprint ""
		(layer "B.Cu")
		(at 332.763876 -66.708782 90)
		(property "Reference" "R3090"
			(at 0 0 90)
			(layer "B.SilkS")
			(hide yes)
			(effects
				(font
					(size 1.27 1.27)
				)
				(justify mirror)
			)
		)
		(property "Value" ""
			(at 0 0 90)
			(layer "B.Fab")
			(effects
				(font
					(size 1.27 1.27)
				)
				(justify mirror)
			)
		)
		(duplicate_pad_numbers_are_jumpers no)
		(fp_line
			(start 0.7874 -0.4064)
			(end -0.7874 -0.4064)
			(stroke
				(width 0.1524)
				(type default)
			)
			(layer "B.SilkS")
		)
		(fp_line
			(start -0.7874 -0.4064)
			(end -0.7874 0.4064)
			(stroke
				(width 0.1524)
				(type default)
			)
			(layer "B.SilkS")
		)
		(fp_line
			(start 0.7874 0.4064)
			(end 0.7874 -0.4064)
			(stroke
				(width 0.1524)
				(type default)
			)
			(layer "B.SilkS")
		)
		(fp_line
			(start -0.7874 0.4064)
			(end 0.7874 0.4064)
			(stroke
				(width 0.1524)
				(type default)
			)
			(layer "B.SilkS")
		)
		(fp_line
			(start 0.67945 -0.305054)
			(end 0.12065 -0.305054)
			(stroke
				(width 0.1)
				(type default)
			)
			(layer "B.Fab")
		)
		(fp_line
			(start 0.12065 -0.305054)
			(end 0.12065 -0.2794)
			(stroke
				(width 0.1)
				(type default)
			)
			(layer "B.Fab")
		)
		(fp_line
			(start -0.12065 -0.3048)
			(end -0.67945 -0.3048)
			(stroke
				(width 0.1)
				(type default)
			)
			(layer "B.Fab")
		)
		(fp_line
			(start -0.67945 -0.3048)
			(end -0.67945 0.3048)
			(stroke
				(width 0.1)
				(type default)
			)
			(layer "B.Fab")
		)
		(fp_line
			(start 0.12065 -0.2794)
			(end -0.12065 -0.2794)
			(stroke
				(width 0.1)
				(type default)
			)
			(layer "B.Fab")
		)
		(fp_line
			(start -0.12065 -0.2794)
			(end -0.12065 -0.3048)
			(stroke
				(width 0.1)
				(type default)
			)
			(layer "B.Fab")
		)
		(fp_line
			(start 0.12065 0.2794)
			(end 0.12065 0.3048)
			(stroke
				(width 0.1)
				(type default)
			)
			(layer "B.Fab")
		)
		(fp_line
			(start -0.120396 0.2794)
			(end 0.12065 0.2794)
			(stroke
				(width 0.1)
				(type default)
			)
			(layer "B.Fab")
		)
		(fp_line
			(start 0.67945 0.3048)
			(end 0.67945 -0.305054)
			(stroke
				(width 0.1)
				(type default)
			)
			(layer "B.Fab")
		)
		(fp_line
			(start 0.12065 0.3048)
			(end 0.67945 0.3048)
			(stroke
				(width 0.1)
				(type default)
			)
			(layer "B.Fab")
		)
		(fp_line
			(start -0.120396 0.3048)
			(end -0.120396 0.2794)
			(stroke
				(width 0.1)
				(type default)
			)
			(layer "B.Fab")
		)
		(fp_line
			(start -0.67945 0.3048)
			(end -0.120396 0.3048)
			(stroke
				(width 0.1)
				(type default)
			)
			(layer "B.Fab")
		)
		(pad "1" smd circle
			(at 0.40005 0 270)
			(size 0 0)
			(layers "B.Cu" "B.Mask" "B.Paste")
			(net "LED_PWRGD_PVDD11_S3_P0_R")
		)
		(pad "2" smd circle
			(at -0.40005 0 270)
			(size 0 0)
			(layers "B.Cu" "B.Mask" "B.Paste")
			(net "P3V3_AUX")
		)
	)
)
